(kicad_pcb
	(version 20260206)
	(generator "pcbnew")
	(generator_version "10.0")
	(general
		(thickness 1.6)
		(legacy_teardrops no)
	)
	(paper "A4")
	(title_block
		(title "panther-plus-userver — 13130-1b_20150205.brd")
		(comment 1 "Honey Badger (Wiwynn) / footprints 1039-1047 of 1509")
	)
	(layers
		(0 "F.Cu" signal "TOP")
		(4 "In1.Cu" signal "L2")
		(6 "In2.Cu" signal "L3")
		(8 "In3.Cu" signal "L4")
		(10 "In4.Cu" signal "L5")
		(12 "In5.Cu" signal "L6")
		(14 "In6.Cu" signal "L7")
		(16 "In7.Cu" signal "L8")
		(18 "In8.Cu" signal "L9")
		(20 "In9.Cu" signal "L10")
		(22 "In10.Cu" signal "L11")
		(2 "B.Cu" signal "BOTTOM")
		(9 "F.Adhes" user "F.Adhesive")
		(11 "B.Adhes" user "B.Adhesive")
		(13 "F.Paste" user "Package Geometry/Pastemask Top")
		(15 "B.Paste" user "Package Geometry/Pastemask Bottom")
		(5 "F.SilkS" user "Ref Des/Silkscreen Top")
		(7 "B.SilkS" user "Ref Des/Silkscreen Bottom")
		(1 "F.Mask" user "Board Geometry/Soldermask Top")
		(3 "B.Mask" user "Board Geometry/Soldermask Bottom")
		(17 "Dwgs.User" user "User.Drawings")
		(19 "Cmts.User" user "User.Comments")
		(21 "Eco1.User" user "User.Eco1")
		(23 "Eco2.User" user "User.Eco2")
		(25 "Edge.Cuts" user "Board Geometry/Outline")
		(27 "Margin" user)
		(31 "F.CrtYd" user "Package Geometry/Place Bound Top")
		(29 "B.CrtYd" user "Package Geometry/Place Bound Bottom")
		(35 "F.Fab" user "Ref Des/Assembly Top")
		(33 "B.Fab" user "Ref Des/Assembly Bottom")
	)
	(footprint ""
		(layer "B.Cu")
		(at 147.828 -59.309)
		(property "Reference" "C359"
			(at 0 0 0)
			(layer "B.SilkS")
			(hide yes)
			(effects
				(font
					(size 1.27 1.27)
				)
				(justify mirror)
			)
		)
		(property "Value" "SC47U6D3V5MX-1-GP"
			(at 0 -4.9022 0)
			(unlocked yes)
			(layer "B.Fab")
			(hide yes)
			(effects
				(font
					(size 1.016 1.016)
					(thickness 0.1524)
				)
				(justify mirror)
			)
		)
		(property "Device Type" "C805H54"
			(at 0 -6.8072 0)
			(unlocked yes)
			(layer "B.Fab")
			(hide yes)
			(effects
				(font
					(size 1.016 1.016)
					(thickness 0.1524)
				)
				(justify mirror)
			)
		)
		(duplicate_pad_numbers_are_jumpers no)
		(fp_line
			(start -0.6096 0)
			(end 0.6096 0)
			(stroke
				(width 0.3048)
				(type default)
			)
			(layer "B.SilkS")
		)
		(fp_poly
			(pts
				(xy 0.9017 1.4351) (xy -0.9017 1.4351) (xy -0.9017 -1.4351) (xy 0.9017 -1.4351)
			)
			(stroke
				(width 0)
				(type default)
			)
			(fill no)
			(layer "B.CrtYd")
		)
		(fp_poly
			(pts
				(xy -0.9017 1.4351) (xy -0.9017 -1.4351) (xy 0.9017 -1.4351) (xy 0.9017 1.4351)
			)
			(stroke
				(width 0)
				(type default)
			)
			(fill no)
			(layer "B.Fab")
		)
		(pad "1" smd rect
			(at 0 -0.8382 180)
			(size 1.5494 0.9398)
			(layers "B.Cu" "B.Mask" "B.Paste")
			(net "PV_VDDR")
		)
		(pad "2" smd rect
			(at 0 0.8382 180)
			(size 1.5494 0.9398)
			(layers "B.Cu" "B.Mask" "B.Paste")
			(net "GND")
		)
	)
	(footprint ""
		(layer "B.Cu")
		(at 203.708 -65.3542 90)
		(property "Reference" "PC154"
			(at 0 0 90)
			(layer "B.SilkS")
			(hide yes)
			(effects
				(font
					(size 1.27 1.27)
				)
				(justify mirror)
			)
		)
		(property "Value" "SC10U6D3V3MX-GP"
			(at 0.0254 -2.0193 90)
			(unlocked yes)
			(layer "B.Fab")
			(hide yes)
			(effects
				(font
					(size 1.016 1.016)
					(thickness 0.1524)
				)
				(justify mirror)
			)
		)
		(property "Device Type" "C603H38"
			(at 0.0254 -3.5433 90)
			(unlocked yes)
			(layer "B.Fab")
			(hide yes)
			(effects
				(font
					(size 1.016 1.016)
					(thickness 0.1524)
				)
				(justify mirror)
			)
		)
		(duplicate_pad_numbers_are_jumpers no)
		(fp_line
			(start 0.4064 0)
			(end -0.4064 0)
			(stroke
				(width 0.2286)
				(type default)
			)
			(layer "B.SilkS")
		)
		(fp_rect
			(start 0.635 1.1811)
			(end -0.635 -1.1811)
			(stroke
				(width 0)
				(type default)
			)
			(fill no)
			(layer "B.CrtYd")
		)
		(fp_rect
			(start 0.635 1.1811)
			(end -0.635 -1.1811)
			(stroke
				(width 0)
				(type default)
			)
			(fill no)
			(layer "B.Fab")
		)
		(pad "1" smd custom
			(at 0 -0.6604 270)
			(size 0.19685 0.19685)
			(layers "B.Cu" "B.Mask" "B.Paste")
			(net "PV_VDDR")
			(options
				(clearance outline)
				(anchor circle)
			)
			(primitives
				(gr_poly
					(pts
						(arc
							(start 0.508 0.2921)
							(mid 0.478242 0.363942)
							(end 0.4064 0.3937)
						)
						(arc
							(start -0.4064 0.3937)
							(mid -0.478242 0.363942)
							(end -0.508 0.2921)
						)
						(arc
							(start -0.508 -0.2921)
							(mid -0.478242 -0.363942)
							(end -0.4064 -0.3937)
						)
						(arc
							(start 0.4064 -0.3937)
							(mid 0.478242 -0.363942)
							(end 0.508 -0.2921)
						)
					)
					(width 0)
					(fill yes)
				)
			)
		)
		(pad "2" smd custom
			(at 0 0.6604 270)
			(size 0.19685 0.19685)
			(layers "B.Cu" "B.Mask" "B.Paste")
			(net "GND")
			(options
				(clearance outline)
				(anchor circle)
			)
			(primitives
				(gr_poly
					(pts
						(arc
							(start 0.508 0.2921)
							(mid 0.478242 0.363942)
							(end 0.4064 0.3937)
						)
						(arc
							(start -0.4064 0.3937)
							(mid -0.478242 0.363942)
							(end -0.508 0.2921)
						)
						(arc
							(start -0.508 -0.2921)
							(mid -0.478242 -0.363942)
							(end -0.4064 -0.3937)
						)
						(arc
							(start 0.4064 -0.3937)
							(mid 0.478242 -0.363942)
							(end 0.508 -0.2921)
						)
					)
					(width 0)
					(fill yes)
				)
			)
		)
	)
	(footprint ""
		(layer "B.Cu")
		(at 25.4 -44.196 -90)
		(property "Reference" "PC139"
			(at 0 0 90)
			(layer "B.SilkS")
			(hide yes)
			(effects
				(font
					(size 1.27 1.27)
				)
				(justify mirror)
			)
		)
		(property "Value" "SC10U6D3V5KX-4GP"
			(at 0 -4.9022 270)
			(unlocked yes)
			(layer "B.Fab")
			(hide yes)
			(effects
				(font
					(size 1.016 1.016)
					(thickness 0.1524)
				)
				(justify mirror)
			)
		)
		(property "Device Type" "C805H58"
			(at 0 -6.8072 270)
			(unlocked yes)
			(layer "B.Fab")
			(hide yes)
			(effects
				(font
					(size 1.016 1.016)
					(thickness 0.1524)
				)
				(justify mirror)
			)
		)
		(duplicate_pad_numbers_are_jumpers no)
		(fp_line
			(start -0.6096 0)
			(end 0.6096 0)
			(stroke
				(width 0.3048)
				(type default)
			)
			(layer "B.SilkS")
		)
		(fp_poly
			(pts
				(xy 0.9017 1.4351) (xy -0.9017 1.4351) (xy -0.9017 -1.4351) (xy 0.9017 -1.4351)
			)
			(stroke
				(width 0)
				(type default)
			)
			(fill no)
			(layer "B.CrtYd")
		)
		(fp_poly
			(pts
				(xy -0.9017 1.4351) (xy -0.9017 -1.4351) (xy 0.9017 -1.4351) (xy 0.9017 1.4351)
			)
			(stroke
				(width 0)
				(type default)
			)
			(fill no)
			(layer "B.Fab")
		)
		(pad "1" smd rect
			(at 0 -0.8382 90)
			(size 1.5494 0.9398)
			(layers "B.Cu" "B.Mask" "B.Paste")
			(net "P1V5_STBY_OUT")
		)
		(pad "2" smd rect
			(at 0 0.8382 90)
			(size 1.5494 0.9398)
			(layers "B.Cu" "B.Mask" "B.Paste")
			(net "GND")
		)
	)
	(footprint ""
		(layer "B.Cu")
		(at 55.3974 -49.9618 180)
		(property "Reference" "PR152"
			(at 0 0 0)
			(layer "B.SilkS")
			(hide yes)
			(effects
				(font
					(size 1.27 1.27)
				)
				(justify mirror)
			)
		)
		(property "Value" "0R2J-2-GP"
			(at -1.7907 -1.1176 180)
			(unlocked yes)
			(layer "B.Fab")
			(hide yes)
			(effects
				(font
					(size 1.016 1.016)
					(thickness 0.1524)
				)
				(justify mirror)
			)
		)
		(property "Device Type" "R402H16"
			(at -1.7907 -2.6416 180)
			(unlocked yes)
			(layer "B.Fab")
			(hide yes)
			(effects
				(font
					(size 1.016 1.016)
					(thickness 0.1524)
				)
				(justify mirror)
			)
		)
		(duplicate_pad_numbers_are_jumpers no)
		(fp_rect
			(start 0.381 0.8382)
			(end -0.381 -0.8382)
			(stroke
				(width 0)
				(type default)
			)
			(fill no)
			(layer "B.CrtYd")
		)
		(fp_rect
			(start 0.381 0.8382)
			(end -0.381 -0.8382)
			(stroke
				(width 0)
				(type default)
			)
			(fill no)
			(layer "B.Fab")
		)
		(pad "1" smd custom
			(at 0 -0.4318)
			(size 0.127 0.127)
			(layers "B.Cu" "B.Mask" "B.Paste")
			(net "P1V5_STBY_PG")
			(options
				(clearance outline)
				(anchor circle)
			)
			(primitives
				(gr_poly
					(pts
						(arc
							(start -0.2032 0.2794)
							(mid -0.239121 0.264521)
							(end -0.254 0.2286)
						)
						(arc
							(start -0.254 -0.2286)
							(mid -0.239121 -0.264521)
							(end -0.2032 -0.2794)
						)
						(arc
							(start 0.2032 -0.2794)
							(mid 0.239121 -0.264521)
							(end 0.254 -0.2286)
						)
						(arc
							(start 0.254 0.2286)
							(mid 0.239121 0.264521)
							(end 0.2032 0.2794)
						)
					)
					(width 0)
					(fill yes)
				)
			)
		)
		(pad "2" smd custom
			(at 0 0.4318)
			(size 0.127 0.127)
			(layers "B.Cu" "B.Mask" "B.Paste")
			(net "VR_EN_P1V0_STBY")
			(options
				(clearance outline)
				(anchor circle)
			)
			(primitives
				(gr_poly
					(pts
						(arc
							(start -0.2032 0.2794)
							(mid -0.239121 0.264521)
							(end -0.254 0.2286)
						)
						(arc
							(start -0.254 -0.2286)
							(mid -0.239121 -0.264521)
							(end -0.2032 -0.2794)
						)
						(arc
							(start 0.2032 -0.2794)
							(mid 0.239121 -0.264521)
							(end 0.254 -0.2286)
						)
						(arc
							(start 0.254 0.2286)
							(mid 0.239121 0.264521)
							(end 0.2032 0.2794)
						)
					)
					(width 0)
					(fill yes)
				)
			)
		)
	)
	(footprint ""
		(layer "B.Cu")
		(at 95.3262 -42.30243 -90)
		(property "Reference" "TP22"
			(at 0 0 90)
			(layer "B.SilkS")
			(hide yes)
			(effects
				(font
					(size 1.27 1.27)
				)
				(justify mirror)
			)
		)
		(property "Value" "TPAD24"
			(at 0 -2.9972 270)
			(unlocked yes)
			(layer "B.Fab")
			(hide yes)
			(effects
				(font
					(size 1.016 1.016)
					(thickness 0.1524)
				)
				(justify mirror)
			)
		)
		(property "Device Type" "TPAD24"
			(at 0 -4.5212 270)
			(unlocked yes)
			(layer "B.Fab")
			(hide yes)
			(effects
				(font
					(size 1.016 1.016)
					(thickness 0.1524)
				)
				(justify mirror)
			)
		)
		(duplicate_pad_numbers_are_jumpers no)
		(fp_poly
			(pts
				(arc
					(start 0 -0.3048)
					(mid 0 0.3048)
					(end 0 -0.3048)
				)
			)
			(stroke
				(width 0)
				(type default)
			)
			(fill no)
			(layer "B.CrtYd")
		)
		(fp_poly
			(pts
				(arc
					(start 0 -0.6096)
					(mid 0 0.6096)
					(end 0 -0.6096)
				)
			)
			(stroke
				(width 0)
				(type default)
			)
			(fill no)
			(layer "B.Fab")
		)
		(pad "1" smd circle
			(at 0 0 90)
			(size 0.6096 0.6096)
			(layers "B.Cu" "B.Mask" "B.Paste")
			(net "TP_CPU_RSVD0")
		)
	)
	(footprint ""
		(layer "B.Cu")
		(at 107.188 -27.321002)
		(property "Reference" "C238"
			(at 0 0 0)
			(layer "B.SilkS")
			(hide yes)
			(effects
				(font
					(size 1.27 1.27)
				)
				(justify mirror)
			)
		)
		(property "Value" "SC1U10V2KX-1GP"
			(at -1.1811 -2.7051 0)
			(unlocked yes)
			(layer "B.Fab")
			(hide yes)
			(effects
				(font
					(size 1.016 1.016)
					(thickness 0.1524)
				)
				(justify mirror)
			)
		)
		(property "Device Type" "C402H22"
			(at -1.1811 -4.2291 0)
			(unlocked yes)
			(layer "B.Fab")
			(hide yes)
			(effects
				(font
					(size 1.016 1.016)
					(thickness 0.1524)
				)
				(justify mirror)
			)
		)
		(duplicate_pad_numbers_are_jumpers no)
		(fp_rect
			(start 0.381 0.7366)
			(end -0.381 -0.7366)
			(stroke
				(width 0)
				(type default)
			)
			(fill no)
			(layer "B.CrtYd")
		)
		(fp_rect
			(start 0.381 0.7366)
			(end -0.381 -0.7366)
			(stroke
				(width 0)
				(type default)
			)
			(fill no)
			(layer "B.Fab")
		)
		(pad "1" smd custom
			(at 0 -0.4572 180)
			(size 0.1143 0.1143)
			(layers "B.Cu" "B.Mask" "B.Paste")
			(net "PV_VDDR")
			(options
				(clearance outline)
				(anchor circle)
			)
			(primitives
				(gr_poly
					(pts
						(arc
							(start -0.254 0.1778)
							(mid -0.239121 0.213721)
							(end -0.2032 0.2286)
						)
						(arc
							(start 0.2032 0.2286)
							(mid 0.239121 0.213721)
							(end 0.254 0.1778)
						)
						(arc
							(start 0.254 -0.1778)
							(mid 0.239121 -0.213721)
							(end 0.2032 -0.2286)
						)
						(arc
							(start -0.2032 -0.2286)
							(mid -0.239121 -0.213721)
							(end -0.254 -0.1778)
						)
					)
					(width 0)
					(fill yes)
				)
			)
		)
		(pad "2" smd custom
			(at 0 0.4572 180)
			(size 0.1143 0.1143)
			(layers "B.Cu" "B.Mask" "B.Paste")
			(net "GND")
			(options
				(clearance outline)
				(anchor circle)
			)
			(primitives
				(gr_poly
					(pts
						(arc
							(start -0.254 0.1778)
							(mid -0.239121 0.213721)
							(end -0.2032 0.2286)
						)
						(arc
							(start 0.2032 0.2286)
							(mid 0.239121 0.213721)
							(end 0.254 0.1778)
						)
						(arc
							(start 0.254 -0.1778)
							(mid 0.239121 -0.213721)
							(end 0.2032 -0.2286)
						)
						(arc
							(start -0.2032 -0.2286)
							(mid -0.239121 -0.213721)
							(end -0.254 -0.1778)
						)
					)
					(width 0)
					(fill yes)
				)
			)
		)
	)
	(footprint ""
		(layer "B.Cu")
		(at 89.1794 -40.4876 -90)
		(property "Reference" "R321"
			(at 0 0 90)
			(layer "B.SilkS")
			(hide yes)
			(effects
				(font
					(size 1.27 1.27)
				)
				(justify mirror)
			)
		)
		(property "Value" "2K2R2F-GP"
			(at -0.064008 -3.993896 270)
			(unlocked yes)
			(layer "B.Fab")
			(hide yes)
			(effects
				(font
					(size 1.016 1.016)
					(thickness 0.1524)
				)
				(justify mirror)
			)
		)
		(property "Device Type" "R402H16"
			(at -0.064008 -5.517896 270)
			(unlocked yes)
			(layer "B.Fab")
			(hide yes)
			(effects
				(font
					(size 1.016 1.016)
					(thickness 0.1524)
				)
				(justify mirror)
			)
		)
		(duplicate_pad_numbers_are_jumpers no)
		(fp_rect
			(start 0.381 0.8382)
			(end -0.381 -0.8382)
			(stroke
				(width 0)
				(type default)
			)
			(fill no)
			(layer "B.CrtYd")
		)
		(fp_rect
			(start 0.381 0.8382)
			(end -0.381 -0.8382)
			(stroke
				(width 0)
				(type default)
			)
			(fill no)
			(layer "B.Fab")
		)
		(pad "1" smd custom
			(at 0 -0.4318 90)
			(size 0.127 0.127)
			(layers "B.Cu" "B.Mask" "B.Paste")
			(net "P3V3")
			(options
				(clearance outline)
				(anchor circle)
			)
			(primitives
				(gr_poly
					(pts
						(arc
							(start -0.2032 0.2794)
							(mid -0.239121 0.264521)
							(end -0.254 0.2286)
						)
						(arc
							(start -0.254 -0.2286)
							(mid -0.239121 -0.264521)
							(end -0.2032 -0.2794)
						)
						(arc
							(start 0.2032 -0.2794)
							(mid 0.239121 -0.264521)
							(end 0.254 -0.2286)
						)
						(arc
							(start 0.254 0.2286)
							(mid 0.239121 0.264521)
							(end 0.2032 0.2794)
						)
					)
					(width 0)
					(fill yes)
				)
			)
		)
		(pad "2" smd custom
			(at 0 0.4318 90)
			(size 0.127 0.127)
			(layers "B.Cu" "B.Mask" "B.Paste")
			(net "LPC_CPU_CLKRUN#")
			(options
				(clearance outline)
				(anchor circle)
			)
			(primitives
				(gr_poly
					(pts
						(arc
							(start -0.2032 0.2794)
							(mid -0.239121 0.264521)
							(end -0.254 0.2286)
						)
						(arc
							(start -0.254 -0.2286)
							(mid -0.239121 -0.264521)
							(end -0.2032 -0.2794)
						)
						(arc
							(start 0.2032 -0.2794)
							(mid 0.239121 -0.264521)
							(end 0.254 -0.2286)
						)
						(arc
							(start 0.254 0.2286)
							(mid 0.239121 0.264521)
							(end 0.2032 0.2794)
						)
					)
					(width 0)
					(fill yes)
				)
			)
		)
	)
	(footprint ""
		(layer "B.Cu")
		(at 45.72 -54.102 -90)
		(property "Reference" "R102"
			(at 0 0 90)
			(layer "B.SilkS")
			(hide yes)
			(effects
				(font
					(size 1.27 1.27)
				)
				(justify mirror)
			)
		)
		(property "Value" "1KR2F-3-GP"
			(at -1.7907 -1.1176 270)
			(unlocked yes)
			(layer "B.Fab")
			(hide yes)
			(effects
				(font
					(size 1.016 1.016)
					(thickness 0.1524)
				)
				(justify mirror)
			)
		)
		(property "Device Type" "R402H16"
			(at -1.7907 -2.6416 270)
			(unlocked yes)
			(layer "B.Fab")
			(hide yes)
			(effects
				(font
					(size 1.016 1.016)
					(thickness 0.1524)
				)
				(justify mirror)
			)
		)
		(duplicate_pad_numbers_are_jumpers no)
		(fp_rect
			(start 0.381 0.8382)
			(end -0.381 -0.8382)
			(stroke
				(width 0)
				(type default)
			)
			(fill no)
			(layer "B.CrtYd")
		)
		(fp_rect
			(start 0.381 0.8382)
			(end -0.381 -0.8382)
			(stroke
				(width 0)
				(type default)
			)
			(fill no)
			(layer "B.Fab")
		)
		(pad "1" smd custom
			(at 0 -0.4318 90)
			(size 0.127 0.127)
			(layers "B.Cu" "B.Mask" "B.Paste")
			(net "CLKREQB")
			(options
				(clearance outline)
				(anchor circle)
			)
			(primitives
				(gr_poly
					(pts
						(arc
							(start -0.2032 0.2794)
							(mid -0.239121 0.264521)
							(end -0.254 0.2286)
						)
						(arc
							(start -0.254 -0.2286)
							(mid -0.239121 -0.264521)
							(end -0.2032 -0.2794)
						)
						(arc
							(start 0.2032 -0.2794)
							(mid 0.239121 -0.264521)
							(end 0.254 -0.2286)
						)
						(arc
							(start 0.254 0.2286)
							(mid 0.239121 0.264521)
							(end 0.2032 0.2794)
						)
					)
					(width 0)
					(fill yes)
				)
			)
		)
		(pad "2" smd custom
			(at 0 0.4318 90)
			(size 0.127 0.127)
			(layers "B.Cu" "B.Mask" "B.Paste")
			(net "GND")
			(options
				(clearance outline)
				(anchor circle)
			)
			(primitives
				(gr_poly
					(pts
						(arc
							(start -0.2032 0.2794)
							(mid -0.239121 0.264521)
							(end -0.254 0.2286)
						)
						(arc
							(start -0.254 -0.2286)
							(mid -0.239121 -0.264521)
							(end -0.2032 -0.2794)
						)
						(arc
							(start 0.2032 -0.2794)
							(mid 0.239121 -0.264521)
							(end 0.254 -0.2286)
						)
						(arc
							(start 0.254 0.2286)
							(mid 0.239121 0.264521)
							(end 0.2032 0.2794)
						)
					)
					(width 0)
					(fill yes)
				)
			)
		)
	)
	(footprint ""
		(layer "B.Cu")
		(at 81.026 -63.246 180)
		(property "Reference" "R288"
			(at 0 0 0)
			(layer "B.SilkS")
			(hide yes)
			(effects
				(font
					(size 1.27 1.27)
				)
				(justify mirror)
			)
		)
		(property "Value" "0R2J-2-GP"
			(at -0.064008 -3.993896 180)
			(unlocked yes)
			(layer "B.Fab")
			(hide yes)
			(effects
				(font
					(size 1.016 1.016)
					(thickness 0.1524)
				)
				(justify mirror)
			)
		)
		(property "Device Type" "R402H16"
			(at -0.064008 -5.517896 180)
			(unlocked yes)
			(layer "B.Fab")
			(hide yes)
			(effects
				(font
					(size 1.016 1.016)
					(thickness 0.1524)
				)
				(justify mirror)
			)
		)
		(duplicate_pad_numbers_are_jumpers no)
		(fp_rect
			(start 0.381 0.8382)
			(end -0.381 -0.8382)
			(stroke
				(width 0)
				(type default)
			)
			(fill no)
			(layer "B.CrtYd")
		)
		(fp_rect
			(start 0.381 0.8382)
			(end -0.381 -0.8382)
			(stroke
				(width 0)
				(type default)
			)
			(fill no)
			(layer "B.Fab")
		)
		(pad "1" smd custom
			(at 0 -0.4318)
			(size 0.127 0.127)
			(layers "B.Cu" "B.Mask" "B.Paste")
			(net "SVID_DATA_R")
			(options
				(clearance outline)
				(anchor circle)
			)
			(primitives
				(gr_poly
					(pts
						(arc
							(start -0.2032 0.2794)
							(mid -0.239121 0.264521)
							(end -0.254 0.2286)
						)
						(arc
							(start -0.254 -0.2286)
							(mid -0.239121 -0.264521)
							(end -0.2032 -0.2794)
						)
						(arc
							(start 0.2032 -0.2794)
							(mid 0.239121 -0.264521)
							(end 0.254 -0.2286)
						)
						(arc
							(start 0.254 0.2286)
							(mid 0.239121 0.264521)
							(end 0.2032 0.2794)
						)
					)
					(width 0)
					(fill yes)
				)
			)
		)
		(pad "2" smd custom
			(at 0 0.4318)
			(size 0.127 0.127)
			(layers "B.Cu" "B.Mask" "B.Paste")
			(net "SVID_CPU_DATA")
			(options
				(clearance outline)
				(anchor circle)
			)
			(primitives
				(gr_poly
					(pts
						(arc
							(start -0.2032 0.2794)
							(mid -0.239121 0.264521)
							(end -0.254 0.2286)
						)
						(arc
							(start -0.254 -0.2286)
							(mid -0.239121 -0.264521)
							(end -0.2032 -0.2794)
						)
						(arc
							(start 0.2032 -0.2794)
							(mid 0.239121 -0.264521)
							(end 0.254 -0.2286)
						)
						(arc
							(start 0.254 0.2286)
							(mid 0.239121 0.264521)
							(end 0.2032 0.2794)
						)
					)
					(width 0)
					(fill yes)
				)
			)
		)
	)
)
